FILE_TYPE = MACRO_DRAWING;
SET COLOR_WIRE YELLOW;
SET COLOR_PROP MONO;
SET COLOR_DOT WHITE;
SET COLOR_ARC YELLOW;
SET COLOR_BODY GREEN;
SET COLOR_NOTE MONO;
SET PROP_DISPLAY VALUE;
SET PAGE_NUMBER P250;
FORCEADD OFFPAGE..1
(-8825 2350);
FORCEPROP 2 LAST $XR0 188 
J 0
(-9077 2350);
DISPLAY 0.638298 (-9077 2350);
PAINT MONO (-9077 2350);
FORCEPROP 2 LAST CDS_LIB mstr_standard
J 0
(-8825 2350);
PAINT MONO (-8825 2350);
DISPLAY INVISIBLE (-8825 2350);
FORCEPROP 2 LAST ROOM PVPP_KLM_VR
J 0
(-9375 2425);
DISPLAY 1.042553 (-9375 2425);
PAINT GREEN (-9375 2425);
DISPLAY INVISIBLE (-9375 2425);
FORCEPROP 2 LAST BOM_COST PVPP_KLM_VR
J 0
(-9650 2425);
DISPLAY 1.042553 (-9650 2425);
PAINT WHITE (-9650 2425);
DISPLAY INVISIBLE (-9650 2425);
FORCEPROP 0 LAST TOLERANCE 1%
J 0
(-8775 2425);
PAINT SKYBLUE (-8775 2425);
DISPLAY INVISIBLE (-8775 2425);
FORCEPROP 2 LAST PATH I1
J 0
(-9250 2400);
DISPLAY 1.021277 (-9250 2400);
PAINT ORANGE (-9250 2400);
DISPLAY INVISIBLE (-9250 2400);
FORCEPROP 1 LAST OFFPAGE TRUE
J 0
(-8500 2225);
PAINT GREEN (-8500 2225);
DISPLAY INVISIBLE (-8500 2225);
FORCEPROP 1 LAST COMMENT_BODY TRUE
J 0
(-8700 2250);
DISPLAY 0.872340 (-8700 2250);
PAINT PEACH (-8700 2250);
DISPLAY INVISIBLE (-8700 2250);
FORCEADD OFFPAGE..2
(-4375 3050);
FORCEPROP 2 LAST $XR1 121 
J 0
(-4066 3050);
DISPLAY 0.638298 (-4066 3050);
PAINT MONO (-4066 3050);
FORCEPROP 2 LAST $XR0 133 
J 0
(-4186 3050);
DISPLAY 0.638298 (-4186 3050);
PAINT MONO (-4186 3050);
FORCEPROP 2 LAST PATH I10
J 0
(-3925 3100);
DISPLAY 1.021277 (-3925 3100);
PAINT ORANGE (-3925 3100);
DISPLAY INVISIBLE (-3925 3100);
FORCEPROP 2 LAST CDS_LIB mstr_standard
J 0
(-4375 3050);
PAINT ORANGE (-4375 3050);
DISPLAY INVISIBLE (-4375 3050);
FORCEPROP 1 LAST OFFPAGE TRUE
J 0
(-4050 2925);
DISPLAY 0.872340 (-4050 2925);
PAINT GREEN (-4050 2925);
DISPLAY INVISIBLE (-4050 2925);
FORCEPROP 1 LAST COMMENT_BODY TRUE
J 0
(-4420 2955);
DISPLAY 0.872340 (-4420 2955);
PAINT GREEN (-4420 2955);
DISPLAY INVISIBLE (-4420 2955);
FORCEADD OFFPAGE..2
(-4975 2300);
FORCEPROP 2 LAST $XR0 145 
J 0
(-4786 2300);
DISPLAY 0.638298 (-4786 2300);
PAINT MONO (-4786 2300);
FORCEPROP 2 LAST CDS_LIB mstr_standard
J 0
(-4975 2300);
PAINT MONO (-4975 2300);
DISPLAY INVISIBLE (-4975 2300);
FORCEPROP 2 LAST PATH I11
J 0
(-4800 2375);
DISPLAY 1.021277 (-4800 2375);
PAINT ORANGE (-4800 2375);
DISPLAY INVISIBLE (-4800 2375);
FORCEPROP 1 LAST OFFPAGE TRUE
J 0
(-4650 2175);
DISPLAY 0.872340 (-4650 2175);
PAINT GREEN (-4650 2175);
DISPLAY INVISIBLE (-4650 2175);
FORCEPROP 1 LAST COMMENT_BODY TRUE
J 0
(-5020 2205);
DISPLAY 0.872340 (-5020 2205);
PAINT GREEN (-5020 2205);
DISPLAY INVISIBLE (-5020 2205);
FORCEADD FET_N_DUAL..5
(-6525 4125);
FORCEPROP 1 LAST MATERIAL FET
J 0
(-6325 4025);
DISPLAY 0.617021 (-6325 4025);
PAINT SKYBLUE (-6325 4025);
FORCEPROP 1 LAST PART_NUMBER D24280-001
J 0
(-6325 3925);
DISPLAY 0.617021 (-6325 3925);
PAINT BLUE (-6325 3925);
FORCEPROP 1 LAST VALUE 2N7002DW
J 0
(-6325 4075);
DISPLAY 0.617021 (-6325 4075);
PAINT SKYBLUE (-6325 4075);
FORCEPROP 1 LAST LOCATION Q1W2
J 0
(-6325 4125);
DISPLAY 0.617021 (-6325 4125);
PAINT AQUA (-6325 4125);
FORCEPROP 1 LASTPIN (-6525 4325) $PN 3
J 2
(-6472 4290);
DISPLAY 0.872340 (-6472 4290);
PAINT WHITE (-6472 4290);
FORCEPROP 1 LASTPIN (-6725 4025) $PN 5
J 2
(-6722 4040);
DISPLAY 0.872340 (-6722 4040);
PAINT WHITE (-6722 4040);
FORCEPROP 1 LASTPIN (-6525 3925) $PN 4
J 2
(-6467 3925);
DISPLAY 0.872340 (-6467 3925);
PAINT WHITE (-6467 3925);
FORCEPROP 0 LAST CDS_SEC 2
J 0
(-6325 4175);
PAINT MONO (-6325 4175);
DISPLAY INVISIBLE (-6325 4175);
FORCEPROP 0 LAST CDS_LOCATION Q1W2
J 0
(-6325 4175);
PAINT MONO (-6325 4175);
DISPLAY INVISIBLE (-6325 4175);
FORCEPROP 2 LAST BOM_COST DEBUG
J 0
(-6325 4225);
DISPLAY 1.021277 (-6325 4225);
PAINT ORANGE (-6325 4225);
DISPLAY INVISIBLE (-6325 4225);
FORCEPROP 2 LAST ROOM UART_MUX
J 0
(-6325 4175);
DISPLAY 1.021277 (-6325 4175);
PAINT ORANGE (-6325 4175);
DISPLAY INVISIBLE (-6325 4175);
FORCEPROP 2 LAST CDS_LIB mstr_discrete
J 0
(-6525 4125);
PAINT MONO (-6525 4125);
DISPLAY INVISIBLE (-6525 4125);
FORCEPROP 1 LAST PACK_TYPE SMLF
J 0
(-6325 3975);
DISPLAY 0.978723 (-6325 3975);
PAINT SKYBLUE (-6325 3975);
DISPLAY INVISIBLE (-6325 3975);
FORCEPROP 0 LAST SEC 2
J 0
(-6325 4175);
DISPLAY 0.680851 (-6325 4175);
PAINT MONO (-6325 4175);
DISPLAY INVISIBLE (-6325 4175);
FORCEPROP 2 LAST SEC_TYPE SMLF
J 0
(-6325 4225);
DISPLAY 1.021277 (-6325 4225);
PAINT ORANGE (-6325 4225);
DISPLAY INVISIBLE (-6325 4225);
FORCEPROP 1 LAST PATH I12
J 0
(-6325 4175);
DISPLAY 0.978723 (-6325 4175);
PAINT BLUE (-6325 4175);
DISPLAY INVISIBLE (-6325 4175);
FORCEADD OFFPAGE..2
(-5375 4375);
FORCEPROP 2 LAST $XR1 121 
J 0
(-5066 4375);
DISPLAY 0.638298 (-5066 4375);
PAINT MONO (-5066 4375);
FORCEPROP 2 LAST $XR0 133 
J 0
(-5186 4375);
DISPLAY 0.638298 (-5186 4375);
PAINT MONO (-5186 4375);
FORCEPROP 2 LAST PATH I13
J 0
(-5050 4425);
DISPLAY 1.021277 (-5050 4425);
PAINT ORANGE (-5050 4425);
DISPLAY INVISIBLE (-5050 4425);
FORCEPROP 2 LAST CDS_LIB mstr_standard
J 0
(-5375 4375);
PAINT ORANGE (-5375 4375);
DISPLAY INVISIBLE (-5375 4375);
FORCEPROP 1 LAST OFFPAGE TRUE
J 0
(-5050 4250);
DISPLAY 0.872340 (-5050 4250);
PAINT GREEN (-5050 4250);
DISPLAY INVISIBLE (-5050 4250);
FORCEPROP 1 LAST COMMENT_BODY TRUE
J 0
(-5420 4280);
DISPLAY 0.872340 (-5420 4280);
PAINT GREEN (-5420 4280);
DISPLAY INVISIBLE (-5420 4280);
FORCEADD OFFPAGE..2
(-6325 5625);
FORCEPROP 2 LAST $XR2 146 
J 0
(-5896 5625);
DISPLAY 0.638298 (-5896 5625);
PAINT MONO (-5896 5625);
FORCEPROP 2 LAST $XR1 119 
J 0
(-6016 5625);
DISPLAY 0.638298 (-6016 5625);
PAINT MONO (-6016 5625);
FORCEPROP 2 LAST $XR0 133 
J 0
(-6136 5625);
DISPLAY 0.638298 (-6136 5625);
PAINT MONO (-6136 5625);
FORCEPROP 2 LAST PATH I14
J 0
(-5875 5675);
DISPLAY 1.021277 (-5875 5675);
PAINT ORANGE (-5875 5675);
DISPLAY INVISIBLE (-5875 5675);
FORCEPROP 2 LAST CDS_LIB mstr_standard
J 0
(-6325 5625);
PAINT ORANGE (-6325 5625);
DISPLAY INVISIBLE (-6325 5625);
FORCEPROP 1 LAST OFFPAGE TRUE
J 0
(-6000 5500);
DISPLAY 0.872340 (-6000 5500);
PAINT GREEN (-6000 5500);
DISPLAY INVISIBLE (-6000 5500);
FORCEPROP 1 LAST COMMENT_BODY TRUE
J 0
(-6370 5530);
DISPLAY 0.872340 (-6370 5530);
PAINT GREEN (-6370 5530);
DISPLAY INVISIBLE (-6370 5530);
FORCEADD OFFPAGE..2
(-5375 5025);
FORCEPROP 2 LAST $XR0 145 
J 0
(-5186 5025);
DISPLAY 0.638298 (-5186 5025);
PAINT MONO (-5186 5025);
FORCEPROP 2 LAST PATH I15
J 0
(-5175 5075);
DISPLAY 1.021277 (-5175 5075);
PAINT ORANGE (-5175 5075);
DISPLAY INVISIBLE (-5175 5075);
FORCEPROP 2 LAST CDS_LIB mstr_standard
J 0
(-5375 5025);
PAINT ORANGE (-5375 5025);
DISPLAY INVISIBLE (-5375 5025);
FORCEPROP 1 LAST OFFPAGE TRUE
J 0
(-5050 4900);
DISPLAY 0.872340 (-5050 4900);
PAINT GREEN (-5050 4900);
DISPLAY INVISIBLE (-5050 4900);
FORCEPROP 1 LAST COMMENT_BODY TRUE
J 0
(-5420 4930);
DISPLAY 0.872340 (-5420 4930);
PAINT GREEN (-5420 4930);
DISPLAY INVISIBLE (-5420 4930);
FORCEADD GND..1
(-6525 3825);
FORCEPROP 3 LASTPIN (-6525 3875) SIG_NAME GND\g
J 0
(-6515 3885);
DISPLAY 0.659574 (-6515 3885);
PAINT MONO (-6515 3885);
DISPLAY INVISIBLE (-6515 3885);
FORCEPROP 1 LAST PATH I16
J 0
(-6450 3825);
DISPLAY 0.872340 (-6450 3825);
PAINT AQUA (-6450 3825);
DISPLAY INVISIBLE (-6450 3825);
FORCEPROP 1 LAST VOLTAGE 0.0V
J 0
(-6570 3782);
DISPLAY 0.340426 (-6570 3782);
PAINT SKYBLUE (-6570 3782);
DISPLAY INVISIBLE (-6570 3782);
FORCEPROP 1 LAST SIZE 1B
J 0
(-6450 3775);
DISPLAY 0.872340 (-6450 3775);
PAINT AQUA (-6450 3775);
DISPLAY INVISIBLE (-6450 3775);
FORCEPROP 2 LAST CDS_LIB mstr_symbols
J 0
(-6525 3825);
PAINT MONO (-6525 3825);
DISPLAY INVISIBLE (-6525 3825);
FORCEPROP 1 LAST BODY_TYPE PLUMBING
J 0
(-6570 3782);
DISPLAY 0.340426 (-6570 3782);
PAINT GREEN (-6570 3782);
DISPLAY INVISIBLE (-6570 3782);
FORCEPROP 1 LAST HDL_POWER GND
J 0
(-6525 3975);
DISPLAY 0.872340 (-6525 3975);
PAINT GREEN (-6525 3975);
DISPLAY INVISIBLE (-6525 3975);
FORCEADD P3V3_STBY..1
(-8300 5725);
FORCEPROP 3 LASTPIN (-8300 5675) SIG_NAME P3V3_STBY\g
J 0
(-8290 5685);
DISPLAY 0.659574 (-8290 5685);
PAINT MONO (-8290 5685);
DISPLAY INVISIBLE (-8290 5685);
FORCEPROP 1 LAST PATH I17
J 0
(-8255 5727);
DISPLAY 0.340426 (-8255 5727);
PAINT GREEN (-8255 5727);
DISPLAY INVISIBLE (-8255 5727);
FORCEPROP 1 LAST SIZE 1B
J 0
(-8255 5747);
DISPLAY 0.340426 (-8255 5747);
PAINT GREEN (-8255 5747);
DISPLAY INVISIBLE (-8255 5747);
FORCEPROP 1 LAST VOLTAGE 3.3V
J 0
(-8345 5682);
DISPLAY 0.340426 (-8345 5682);
PAINT SKYBLUE (-8345 5682);
DISPLAY INVISIBLE (-8345 5682);
FORCEPROP 2 LAST CDS_LIB mstr_symbols
J 0
(-8300 5725);
PAINT MONO (-8300 5725);
DISPLAY INVISIBLE (-8300 5725);
FORCEPROP 1 LAST BODY_TYPE PLUMBING
J 0
(-8345 5682);
DISPLAY 0.340426 (-8345 5682);
PAINT GREEN (-8345 5682);
DISPLAY INVISIBLE (-8345 5682);
FORCEPROP 1 LAST HDL_POWER P3V3_STBY
J 0
(-8600 5600);
DISPLAY 0.872340 (-8600 5600);
PAINT ORANGE (-8600 5600);
DISPLAY INVISIBLE (-8600 5600);
FORCEADD 1MR2F-L-GP..1
(-8300 5500);
FORCEPROP 2 LAST RATED 1/16W
J 0
(-8275 5375);
DISPLAY 0.638298 (-8275 5375);
PAINT GREEN (-8275 5375);
FORCEPROP 2 LAST TOLERANCE 1%
J 0
(-8275 5425);
DISPLAY 0.638298 (-8275 5425);
PAINT GREEN (-8275 5425);
FORCEPROP 1 LAST VALUE 1MR2F-L-GP
J 0
(-8275 5525);
DISPLAY 0.617021 (-8275 5525);
PAINT GREEN (-8275 5525);
FORCEPROP 0 LASTPIN (-8300 5625) $PN 1
R 1
J 0
(-8310 5635);
DISPLAY 0.808511 (-8310 5635);
PAINT MONO (-8310 5635);
FORCEPROP 0 LASTPIN (-8300 5375) $PN 2
R 1
J 2
(-8310 5365);
DISPLAY 0.808511 (-8310 5365);
PAINT MONO (-8310 5365);
FORCEPROP 2 LAST ATTRIBUTE 1MOHM
J 0
(-8275 5475);
DISPLAY 0.638298 (-8275 5475);
PAINT GREEN (-8275 5475);
FORCEPROP 2 LAST PACK_SIZE 0402
J 0
(-8275 5325);
DISPLAY 0.638298 (-8275 5325);
PAINT GREEN (-8275 5325);
FORCEPROP 1 LAST LOCATION R1W1
J 0
(-8275 5580);
DISPLAY 0.617021 (-8275 5580);
PAINT GREEN (-8275 5580);
FORCEPROP 1 LAST PATH I18
J 0
(-8300 5500);
DISPLAY 0.617021 (-8300 5500);
PAINT GREEN (-8300 5500);
DISPLAY INVISIBLE (-8300 5500);
FORCEPROP 1 LAST CDS_LMAN_SYM_OUTLINE -50,75,50,-75
J 0
(-8300 5500);
DISPLAY 0.468085 (-8300 5500);
PAINT GREEN (-8300 5500);
DISPLAY INVISIBLE (-8300 5500);
FORCEPROP 2 LAST CDS_LIB w_hdl
J 0
(-8300 5500);
PAINT MONO (-8300 5500);
DISPLAY INVISIBLE (-8300 5500);
FORCEPROP 1 LAST PART_NUMBER 64.10045.L1L
J 0
(-8300 5500);
DISPLAY 0.617021 (-8300 5500);
PAINT GREEN (-8300 5500);
DISPLAY INVISIBLE (-8300 5500);
FORCEPROP 1 LAST PACK_TYPE SMD-RG1
J 0
(-8300 5500);
DISPLAY 0.617021 (-8300 5500);
PAINT GREEN (-8300 5500);
DISPLAY INVISIBLE (-8300 5500);
FORCEPROP 0 LAST CDS_LOCATION R1W1
J 0
(-8275 5625);
PAINT MONO (-8275 5625);
DISPLAY INVISIBLE (-8275 5625);
FORCEPROP 0 LAST $SEC 1
J 0
(-8275 5625);
PAINT MONO (-8275 5625);
DISPLAY INVISIBLE (-8275 5625);
FORCEPROP 0 LAST CDS_SEC 1
J 0
(-8275 5625);
PAINT MONO (-8275 5625);
DISPLAY INVISIBLE (-8275 5625);
FORCEADD GND..1
(-7350 5075);
FORCEPROP 3 LASTPIN (-7350 5125) SIG_NAME GND\g
J 0
(-7340 5135);
DISPLAY 0.659574 (-7340 5135);
PAINT MONO (-7340 5135);
DISPLAY INVISIBLE (-7340 5135);
FORCEPROP 1 LAST PATH I19
J 0
(-7275 5075);
DISPLAY 0.872340 (-7275 5075);
PAINT AQUA (-7275 5075);
DISPLAY INVISIBLE (-7275 5075);
FORCEPROP 1 LAST VOLTAGE 0.0V
J 0
(-7395 5032);
DISPLAY 0.340426 (-7395 5032);
PAINT SKYBLUE (-7395 5032);
DISPLAY INVISIBLE (-7395 5032);
FORCEPROP 1 LAST SIZE 1B
J 0
(-7275 5025);
DISPLAY 0.872340 (-7275 5025);
PAINT AQUA (-7275 5025);
DISPLAY INVISIBLE (-7275 5025);
FORCEPROP 2 LAST CDS_LIB mstr_symbols
J 0
(-7350 5075);
PAINT MONO (-7350 5075);
DISPLAY INVISIBLE (-7350 5075);
FORCEPROP 1 LAST BODY_TYPE PLUMBING
J 0
(-7395 5032);
DISPLAY 0.340426 (-7395 5032);
PAINT GREEN (-7395 5032);
DISPLAY INVISIBLE (-7395 5032);
FORCEPROP 1 LAST HDL_POWER GND
J 0
(-7350 5225);
DISPLAY 0.872340 (-7350 5225);
PAINT GREEN (-7350 5225);
DISPLAY INVISIBLE (-7350 5225);
FORCEADD 1MR2F-L-GP..1
(-8725 2575);
FORCEPROP 1 LAST LOCATION R1W6
J 0
(-8700 2680);
DISPLAY 0.617021 (-8700 2680);
PAINT GREEN (-8700 2680);
FORCEPROP 2 LAST TOLERANCE 1%
J 0
(-8700 2525);
DISPLAY 0.638298 (-8700 2525);
PAINT GREEN (-8700 2525);
FORCEPROP 0 LASTPIN (-8725 2700) $PN 1
R 1
J 0
(-8735 2710);
DISPLAY 0.808511 (-8735 2710);
PAINT MONO (-8735 2710);
FORCEPROP 0 LASTPIN (-8725 2450) $PN 2
R 1
J 2
(-8735 2440);
DISPLAY 0.808511 (-8735 2440);
PAINT MONO (-8735 2440);
FORCEPROP 2 LAST PACK_SIZE 0402
J 0
(-8700 2425);
DISPLAY 0.638298 (-8700 2425);
PAINT GREEN (-8700 2425);
FORCEPROP 2 LAST RATED 1/16W
J 0
(-8700 2475);
DISPLAY 0.638298 (-8700 2475);
PAINT GREEN (-8700 2475);
FORCEPROP 2 LAST ATTRIBUTE 1MOHM
J 0
(-8700 2575);
DISPLAY 0.638298 (-8700 2575);
PAINT GREEN (-8700 2575);
FORCEPROP 1 LAST VALUE 1MR2F-L-GP
J 0
(-8700 2625);
DISPLAY 0.617021 (-8700 2625);
PAINT GREEN (-8700 2625);
FORCEPROP 1 LAST CDS_LMAN_SYM_OUTLINE -50,75,50,-75
J 0
(-8725 2575);
DISPLAY 0.468085 (-8725 2575);
PAINT GREEN (-8725 2575);
DISPLAY INVISIBLE (-8725 2575);
FORCEPROP 2 LAST CDS_LIB w_hdl
J 0
(-8725 2575);
PAINT MONO (-8725 2575);
DISPLAY INVISIBLE (-8725 2575);
FORCEPROP 1 LAST PART_NUMBER 64.10045.L1L
J 0
(-8725 2575);
DISPLAY 0.617021 (-8725 2575);
PAINT GREEN (-8725 2575);
DISPLAY INVISIBLE (-8725 2575);
FORCEPROP 1 LAST PACK_TYPE SMD-RG1
J 0
(-8725 2575);
DISPLAY 0.617021 (-8725 2575);
PAINT GREEN (-8725 2575);
DISPLAY INVISIBLE (-8725 2575);
FORCEPROP 0 LAST $SEC 1
J 0
(-8700 2700);
PAINT MONO (-8700 2700);
DISPLAY INVISIBLE (-8700 2700);
FORCEPROP 0 LAST CDS_SEC 1
J 0
(-8700 2700);
PAINT MONO (-8700 2700);
DISPLAY INVISIBLE (-8700 2700);
FORCEPROP 1 LAST PATH I2
J 0
(-8725 2575);
DISPLAY 0.617021 (-8725 2575);
PAINT GREEN (-8725 2575);
DISPLAY INVISIBLE (-8725 2575);
FORCEPROP 0 LAST CDS_LOCATION R1W6
J 0
(-8700 2700);
PAINT MONO (-8700 2700);
DISPLAY INVISIBLE (-8700 2700);
FORCEADD P3V3_STBY..1
(-7350 4900);
FORCEPROP 3 LASTPIN (-7350 4850) SIG_NAME P3V3_STBY\g
J 0
(-7340 4860);
DISPLAY 0.659574 (-7340 4860);
PAINT MONO (-7340 4860);
DISPLAY INVISIBLE (-7340 4860);
FORCEPROP 1 LAST PATH I21
J 0
(-7305 4902);
DISPLAY 0.340426 (-7305 4902);
PAINT GREEN (-7305 4902);
DISPLAY INVISIBLE (-7305 4902);
FORCEPROP 2 LAST CDS_LIB mstr_symbols
J 0
(-7350 4900);
PAINT MONO (-7350 4900);
DISPLAY INVISIBLE (-7350 4900);
FORCEPROP 1 LAST SIZE 1B
J 0
(-7305 4922);
DISPLAY 0.340426 (-7305 4922);
PAINT GREEN (-7305 4922);
DISPLAY INVISIBLE (-7305 4922);
FORCEPROP 1 LAST VOLTAGE 3.3V
J 0
(-7395 4857);
DISPLAY 0.340426 (-7395 4857);
PAINT SKYBLUE (-7395 4857);
DISPLAY INVISIBLE (-7395 4857);
FORCEPROP 1 LAST BODY_TYPE PLUMBING
J 0
(-7395 4857);
DISPLAY 0.340426 (-7395 4857);
PAINT GREEN (-7395 4857);
DISPLAY INVISIBLE (-7395 4857);
FORCEPROP 1 LAST HDL_POWER P3V3_STBY
J 0
(-7650 4775);
DISPLAY 0.872340 (-7650 4775);
PAINT ORANGE (-7650 4775);
DISPLAY INVISIBLE (-7650 4775);
FORCEADD RES..1
R 1
(-7350 4700);
FORCEPROP 1 LAST WATTAGE 1/16W
J 2
(-7175 4700);
DISPLAY 0.617021 (-7175 4700);
PAINT SKYBLUE (-7175 4700);
FORCEPROP 1 LASTPIN (-7350 4600) $PN 1
R 1
J 0
(-7362 4612);
DISPLAY 0.787234 (-7362 4612);
PAINT ORANGE (-7362 4612);
FORCEPROP 1 LAST PART_NUMBER G21796-016
J 0
(-7275 4600);
DISPLAY 0.617021 (-7275 4600);
PAINT BLUE (-7275 4600);
FORCEPROP 1 LAST PACK_TYPE 0402
J 0
(-7275 4550);
DISPLAY 0.617021 (-7275 4550);
PAINT SKYBLUE (-7275 4550);
FORCEPROP 1 LAST MATERIAL CHIP
J 0
(-7275 4650);
DISPLAY 0.617021 (-7275 4650);
PAINT SKYBLUE (-7275 4650);
FORCEPROP 1 LASTPIN (-7350 4800) $PN 2
R 1
J 0
(-7362 4762);
DISPLAY 0.787234 (-7362 4762);
PAINT ORANGE (-7362 4762);
FORCEPROP 1 LAST LOCATION R1W4
J 0
(-7275 4850);
DISPLAY 0.617021 (-7275 4850);
PAINT AQUA (-7275 4850);
FORCEPROP 1 LAST TOLERANCE 1%
J 0
(-7275 4750);
DISPLAY 0.617021 (-7275 4750);
PAINT SKYBLUE (-7275 4750);
FORCEPROP 1 LAST VALUE 10.0K
J 2
(-7175 4800);
DISPLAY 0.617021 (-7175 4800);
PAINT SKYBLUE (-7175 4800);
FORCEPROP 1 LAST PATH I22
R 1
J 0
(-7500 4650);
DISPLAY 0.978723 (-7500 4650);
PAINT WHITE (-7500 4650);
DISPLAY INVISIBLE (-7500 4650);
FORCEPROP 0 LAST CDS_SEC 1
R 1
J 0
(-7275 4900);
PAINT MONO (-7275 4900);
DISPLAY INVISIBLE (-7275 4900);
FORCEPROP 0 LAST CDS_LOCATION R1W4
R 1
J 0
(-7275 4900);
PAINT MONO (-7275 4900);
DISPLAY INVISIBLE (-7275 4900);
FORCEPROP 0 LAST ROOM SB
R 1
J 0
(-7500 4650);
DISPLAY 1.021277 (-7500 4650);
PAINT ORANGE (-7500 4650);
DISPLAY INVISIBLE (-7500 4650);
FORCEPROP 2 LAST CDS_LIB mstr_discrete
R 1
J 0
(-7350 4700);
PAINT MONO (-7350 4700);
DISPLAY INVISIBLE (-7350 4700);
FORCEPROP 0 LAST SEC 1
R 1
J 0
(-7275 4900);
DISPLAY 0.680851 (-7275 4900);
PAINT MONO (-7275 4900);
DISPLAY INVISIBLE (-7275 4900);
FORCEPROP 2 LAST SEC_TYPE 0402
J 0
(-7275 4900);
DISPLAY 1.021277 (-7275 4900);
PAINT ORANGE (-7275 4900);
DISPLAY INVISIBLE (-7275 4900);
FORCEADD GND..1
(-7350 3950);
FORCEPROP 3 LASTPIN (-7350 4000) SIG_NAME GND\g
J 0
(-7340 4010);
DISPLAY 0.659574 (-7340 4010);
PAINT MONO (-7340 4010);
DISPLAY INVISIBLE (-7340 4010);
FORCEPROP 1 LAST PATH I23
J 0
(-7275 3950);
DISPLAY 0.872340 (-7275 3950);
PAINT AQUA (-7275 3950);
DISPLAY INVISIBLE (-7275 3950);
FORCEPROP 2 LAST CDS_LIB mstr_symbols
J 0
(-7350 3950);
PAINT MONO (-7350 3950);
DISPLAY INVISIBLE (-7350 3950);
FORCEPROP 1 LAST SIZE 1B
J 0
(-7275 3900);
DISPLAY 0.872340 (-7275 3900);
PAINT AQUA (-7275 3900);
DISPLAY INVISIBLE (-7275 3900);
FORCEPROP 1 LAST VOLTAGE 0.0V
J 0
(-7395 3907);
DISPLAY 0.340426 (-7395 3907);
PAINT SKYBLUE (-7395 3907);
DISPLAY INVISIBLE (-7395 3907);
FORCEPROP 1 LAST BODY_TYPE PLUMBING
J 0
(-7395 3907);
DISPLAY 0.340426 (-7395 3907);
PAINT GREEN (-7395 3907);
DISPLAY INVISIBLE (-7395 3907);
FORCEPROP 1 LAST HDL_POWER GND
J 0
(-7350 4100);
DISPLAY 0.872340 (-7350 4100);
PAINT GREEN (-7350 4100);
DISPLAY INVISIBLE (-7350 4100);
FORCEADD FET_N_DUAL..5
(-7350 4250);
FORCEPROP 1 LASTPIN (-7350 4050) $PN 1
J 2
(-7292 4050);
DISPLAY 0.872340 (-7292 4050);
PAINT WHITE (-7292 4050);
FORCEPROP 1 LASTPIN (-7550 4150) $PN 2
J 2
(-7547 4165);
DISPLAY 0.872340 (-7547 4165);
PAINT WHITE (-7547 4165);
FORCEPROP 1 LAST VALUE 2N7002DW
J 0
(-7150 4200);
DISPLAY 0.617021 (-7150 4200);
PAINT SKYBLUE (-7150 4200);
FORCEPROP 1 LAST MATERIAL FET
J 0
(-7150 4150);
DISPLAY 0.617021 (-7150 4150);
PAINT SKYBLUE (-7150 4150);
FORCEPROP 1 LAST PART_NUMBER D24280-001
J 0
(-7150 4100);
DISPLAY 0.617021 (-7150 4100);
PAINT BLUE (-7150 4100);
FORCEPROP 1 LASTPIN (-7350 4450) $PN 6
J 2
(-7297 4415);
DISPLAY 0.872340 (-7297 4415);
PAINT WHITE (-7297 4415);
FORCEPROP 1 LAST LOCATION Q1W2
J 0
(-7150 4250);
DISPLAY 0.617021 (-7150 4250);
PAINT AQUA (-7150 4250);
FORCEPROP 0 LAST CDS_SEC 1
J 0
(-7150 4300);
PAINT MONO (-7150 4300);
DISPLAY INVISIBLE (-7150 4300);
FORCEPROP 0 LAST CDS_LOCATION Q1W2
J 0
(-7150 4300);
PAINT MONO (-7150 4300);
DISPLAY INVISIBLE (-7150 4300);
FORCEPROP 2 LAST SEC_TYPE SMLF
J 0
(-7150 4350);
DISPLAY 1.021277 (-7150 4350);
PAINT ORANGE (-7150 4350);
DISPLAY INVISIBLE (-7150 4350);
FORCEPROP 2 LAST SEC 1
J 0
(-7150 4350);
DISPLAY 0.680851 (-7150 4350);
PAINT MONO (-7150 4350);
DISPLAY INVISIBLE (-7150 4350);
FORCEPROP 1 LAST PACK_TYPE SMLF
J 0
(-7150 4100);
DISPLAY 0.978723 (-7150 4100);
PAINT SKYBLUE (-7150 4100);
DISPLAY INVISIBLE (-7150 4100);
FORCEPROP 2 LAST CDS_LIB mstr_discrete
J 0
(-7350 4250);
PAINT MONO (-7350 4250);
DISPLAY INVISIBLE (-7350 4250);
FORCEPROP 2 LAST BOM_COST DEBUG
J 0
(-7150 4350);
DISPLAY 1.021277 (-7150 4350);
PAINT ORANGE (-7150 4350);
DISPLAY INVISIBLE (-7150 4350);
FORCEPROP 2 LAST ROOM UART_MUX
J 0
(-7150 4300);
DISPLAY 1.021277 (-7150 4300);
PAINT ORANGE (-7150 4300);
DISPLAY INVISIBLE (-7150 4300);
FORCEPROP 1 LAST PATH I24
J 0
(-7150 4300);
DISPLAY 0.978723 (-7150 4300);
PAINT BLUE (-7150 4300);
DISPLAY INVISIBLE (-7150 4300);
FORCEADD OFFPAGE..1
(-8400 5275);
FORCEPROP 2 LAST $XR0 186 
J 0
(-8832 5275);
DISPLAY 0.638298 (-8832 5275);
PAINT MONO (-8832 5275);
FORCEPROP 2 LAST PATH I25
J 0
(-8650 5325);
DISPLAY 1.021277 (-8650 5325);
PAINT ORANGE (-8650 5325);
DISPLAY INVISIBLE (-8650 5325);
FORCEPROP 2 LAST CDS_LIB mstr_standard
J 0
(-8400 5275);
PAINT MONO (-8400 5275);
DISPLAY INVISIBLE (-8400 5275);
FORCEPROP 2 LAST ROOM PVPP_KLM_VR
J 0
(-8950 5350);
DISPLAY 1.042553 (-8950 5350);
PAINT GREEN (-8950 5350);
DISPLAY INVISIBLE (-8950 5350);
FORCEPROP 2 LAST BOM_COST PVPP_KLM_VR
J 0
(-9225 5350);
DISPLAY 1.042553 (-9225 5350);
PAINT WHITE (-9225 5350);
DISPLAY INVISIBLE (-9225 5350);
FORCEPROP 0 LAST TOLERANCE 1%
J 0
(-8350 5350);
PAINT SKYBLUE (-8350 5350);
DISPLAY INVISIBLE (-8350 5350);
FORCEPROP 1 LAST OFFPAGE TRUE
J 0
(-8075 5150);
PAINT GREEN (-8075 5150);
DISPLAY INVISIBLE (-8075 5150);
FORCEPROP 1 LAST COMMENT_BODY TRUE
J 0
(-8275 5175);
DISPLAY 0.872340 (-8275 5175);
PAINT PEACH (-8275 5175);
DISPLAY INVISIBLE (-8275 5175);
FORCEADD P3V3_STBY..1
(-8300 4575);
FORCEPROP 3 LASTPIN (-8300 4525) SIG_NAME P3V3_STBY\g
J 0
(-8290 4535);
DISPLAY 0.659574 (-8290 4535);
PAINT MONO (-8290 4535);
DISPLAY INVISIBLE (-8290 4535);
FORCEPROP 1 LAST PATH I26
J 0
(-8255 4577);
DISPLAY 0.340426 (-8255 4577);
PAINT GREEN (-8255 4577);
DISPLAY INVISIBLE (-8255 4577);
FORCEPROP 1 LAST SIZE 1B
J 0
(-8255 4597);
DISPLAY 0.340426 (-8255 4597);
PAINT GREEN (-8255 4597);
DISPLAY INVISIBLE (-8255 4597);
FORCEPROP 1 LAST VOLTAGE 3.3V
J 0
(-8345 4532);
DISPLAY 0.340426 (-8345 4532);
PAINT SKYBLUE (-8345 4532);
DISPLAY INVISIBLE (-8345 4532);
FORCEPROP 2 LAST CDS_LIB mstr_symbols
J 0
(-8300 4575);
PAINT MONO (-8300 4575);
DISPLAY INVISIBLE (-8300 4575);
FORCEPROP 1 LAST BODY_TYPE PLUMBING
J 0
(-8345 4532);
DISPLAY 0.340426 (-8345 4532);
PAINT GREEN (-8345 4532);
DISPLAY INVISIBLE (-8345 4532);
FORCEPROP 1 LAST HDL_POWER P3V3_STBY
J 0
(-8600 4450);
DISPLAY 0.872340 (-8600 4450);
PAINT ORANGE (-8600 4450);
DISPLAY INVISIBLE (-8600 4450);
FORCEADD 1MR2F-L-GP..1
(-8300 4350);
FORCEPROP 1 LAST LOCATION R1W3
J 0
(-8250 4480);
DISPLAY 0.617021 (-8250 4480);
PAINT GREEN (-8250 4480);
FORCEPROP 1 LAST VALUE 1MR2F-L-GP
J 0
(-8250 4425);
DISPLAY 0.617021 (-8250 4425);
PAINT GREEN (-8250 4425);
FORCEPROP 2 LAST ATTRIBUTE 1MOHM
J 0
(-8250 4375);
DISPLAY 0.638298 (-8250 4375);
PAINT GREEN (-8250 4375);
FORCEPROP 2 LAST RATED 1/16W
J 0
(-8250 4275);
DISPLAY 0.638298 (-8250 4275);
PAINT GREEN (-8250 4275);
FORCEPROP 0 LASTPIN (-8300 4225) $PN 2
R 1
J 2
(-8310 4215);
DISPLAY 0.808511 (-8310 4215);
PAINT MONO (-8310 4215);
FORCEPROP 0 LASTPIN (-8300 4475) $PN 1
R 1
J 0
(-8310 4485);
DISPLAY 0.808511 (-8310 4485);
PAINT MONO (-8310 4485);
FORCEPROP 2 LAST TOLERANCE 1%
J 0
(-8250 4325);
DISPLAY 0.638298 (-8250 4325);
PAINT GREEN (-8250 4325);
FORCEPROP 2 LAST PACK_SIZE 0402
J 0
(-8250 4225);
DISPLAY 0.638298 (-8250 4225);
PAINT GREEN (-8250 4225);
FORCEPROP 1 LAST PATH I27
J 0
(-8300 4350);
DISPLAY 0.617021 (-8300 4350);
PAINT GREEN (-8300 4350);
DISPLAY INVISIBLE (-8300 4350);
FORCEPROP 0 LAST CDS_SEC 1
J 0
(-8275 4475);
PAINT MONO (-8275 4475);
DISPLAY INVISIBLE (-8275 4475);
FORCEPROP 0 LAST $SEC 1
J 0
(-8275 4475);
PAINT MONO (-8275 4475);
DISPLAY INVISIBLE (-8275 4475);
FORCEPROP 0 LAST CDS_LOCATION R1W3
J 0
(-8275 4475);
PAINT MONO (-8275 4475);
DISPLAY INVISIBLE (-8275 4475);
FORCEPROP 1 LAST PACK_TYPE SMD-RG1
J 0
(-8300 4350);
DISPLAY 0.617021 (-8300 4350);
PAINT GREEN (-8300 4350);
DISPLAY INVISIBLE (-8300 4350);
FORCEPROP 1 LAST PART_NUMBER 64.10045.L1L
J 0
(-8300 4350);
DISPLAY 0.617021 (-8300 4350);
PAINT GREEN (-8300 4350);
DISPLAY INVISIBLE (-8300 4350);
FORCEPROP 2 LAST CDS_LIB w_hdl
J 0
(-8300 4350);
PAINT MONO (-8300 4350);
DISPLAY INVISIBLE (-8300 4350);
FORCEPROP 1 LAST CDS_LMAN_SYM_OUTLINE -50,75,50,-75
J 0
(-8300 4350);
DISPLAY 0.468085 (-8300 4350);
PAINT GREEN (-8300 4350);
DISPLAY INVISIBLE (-8300 4350);
FORCEADD OFFPAGE..1
(-8400 4150);
FORCEPROP 2 LAST $XR0 187 
J 0
(-8832 4150);
DISPLAY 0.638298 (-8832 4150);
PAINT MONO (-8832 4150);
FORCEPROP 2 LAST PATH I28
J 0
(-8650 4200);
DISPLAY 1.021277 (-8650 4200);
PAINT ORANGE (-8650 4200);
DISPLAY INVISIBLE (-8650 4200);
FORCEPROP 0 LAST TOLERANCE 1%
J 0
(-8350 4225);
PAINT SKYBLUE (-8350 4225);
DISPLAY INVISIBLE (-8350 4225);
FORCEPROP 2 LAST BOM_COST PVPP_KLM_VR
J 0
(-9225 4225);
DISPLAY 1.042553 (-9225 4225);
PAINT WHITE (-9225 4225);
DISPLAY INVISIBLE (-9225 4225);
FORCEPROP 2 LAST ROOM PVPP_KLM_VR
J 0
(-8950 4225);
DISPLAY 1.042553 (-8950 4225);
PAINT GREEN (-8950 4225);
DISPLAY INVISIBLE (-8950 4225);
FORCEPROP 2 LAST CDS_LIB mstr_standard
J 0
(-8400 4150);
PAINT MONO (-8400 4150);
DISPLAY INVISIBLE (-8400 4150);
FORCEPROP 1 LAST OFFPAGE TRUE
J 0
(-8075 4025);
PAINT GREEN (-8075 4025);
DISPLAY INVISIBLE (-8075 4025);
FORCEPROP 1 LAST COMMENT_BODY TRUE
J 0
(-8275 4050);
DISPLAY 0.872340 (-8275 4050);
PAINT PEACH (-8275 4050);
DISPLAY INVISIBLE (-8275 4050);
FORCEADD FET_N..8
(-7350 5375);
FORCEPROP 1 LAST LOCATION Q1W1
J 0
(-7150 5375);
DISPLAY 0.617021 (-7150 5375);
PAINT AQUA (-7150 5375);
FORCEPROP 1 LASTPIN (-7350 5575) $PN 3
J 2
(-7297 5540);
DISPLAY 0.617021 (-7297 5540);
PAINT WHITE (-7297 5540);
FORCEPROP 1 LAST VALUE 2N7002
J 0
(-7150 5325);
DISPLAY 0.617021 (-7150 5325);
PAINT SKYBLUE (-7150 5325);
FORCEPROP 1 LASTPIN (-7350 5175) $PN 2
J 2
(-7292 5175);
DISPLAY 0.617021 (-7292 5175);
PAINT WHITE (-7292 5175);
FORCEPROP 1 LAST MATERIAL FET
J 0
(-7150 5275);
DISPLAY 0.617021 (-7150 5275);
PAINT SKYBLUE (-7150 5275);
FORCEPROP 1 LAST PART_NUMBER C79254-001
J 0
(-7150 5175);
DISPLAY 0.617021 (-7150 5175);
PAINT BLUE (-7150 5175);
FORCEPROP 1 LASTPIN (-7550 5275) $PN 1
J 2
(-7547 5290);
DISPLAY 0.617021 (-7547 5290);
PAINT WHITE (-7547 5290);
FORCEPROP 2 LAST CDS_LOCATION Q1W1
J 0
(-7150 5375);
DISPLAY 0.617021 (-7150 5375);
PAINT AQUA (-7150 5375);
DISPLAY INVISIBLE (-7150 5375);
FORCEPROP 1 LAST PATH I29
J 0
(-7150 5425);
DISPLAY 0.978723 (-7150 5425);
PAINT BLUE (-7150 5425);
DISPLAY INVISIBLE (-7150 5425);
FORCEPROP 2 LAST CDS_LIB mstr_discrete
J 0
(-7350 5375);
PAINT ORANGE (-7350 5375);
DISPLAY INVISIBLE (-7350 5375);
FORCEPROP 2 LAST SEC 1
J 0
(-7150 5475);
DISPLAY 0.680851 (-7150 5475);
PAINT MONO (-7150 5475);
DISPLAY INVISIBLE (-7150 5475);
FORCEPROP 2 LAST SEC_TYPE SOT23LF
J 0
(-7150 5475);
DISPLAY 1.021277 (-7150 5475);
PAINT ORANGE (-7150 5475);
DISPLAY INVISIBLE (-7150 5475);
FORCEPROP 0 LAST ROOM HOT_SWAP
J 0
(-7150 5475);
DISPLAY 1.021277 (-7150 5475);
PAINT ORANGE (-7150 5475);
DISPLAY INVISIBLE (-7150 5475);
FORCEPROP 1 LAST PACK_TYPE SOT23LF
J 0
(-7150 5225);
DISPLAY 0.978723 (-7150 5225);
PAINT SKYBLUE (-7150 5225);
DISPLAY INVISIBLE (-7150 5225);
FORCEADD FET_N_DUAL..5
(-7700 2450);
FORCEPROP 1 LAST PART_NUMBER D24280-001
J 0
(-7500 2250);
DISPLAY 0.617021 (-7500 2250);
PAINT BLUE (-7500 2250);
FORCEPROP 1 LAST MATERIAL FET
J 0
(-7500 2350);
DISPLAY 0.617021 (-7500 2350);
PAINT SKYBLUE (-7500 2350);
FORCEPROP 1 LAST VALUE 2N7002DW
J 0
(-7500 2400);
DISPLAY 0.617021 (-7500 2400);
PAINT SKYBLUE (-7500 2400);
FORCEPROP 1 LAST LOCATION Q1W4
J 0
(-7500 2450);
DISPLAY 0.617021 (-7500 2450);
PAINT AQUA (-7500 2450);
FORCEPROP 1 LASTPIN (-7900 2350) $PN 2
J 2
(-7897 2365);
DISPLAY 0.872340 (-7897 2365);
PAINT WHITE (-7897 2365);
FORCEPROP 1 LASTPIN (-7700 2250) $PN 1
J 2
(-7642 2250);
DISPLAY 0.872340 (-7642 2250);
PAINT WHITE (-7642 2250);
FORCEPROP 1 LASTPIN (-7700 2650) $PN 6
J 2
(-7647 2615);
DISPLAY 0.872340 (-7647 2615);
PAINT WHITE (-7647 2615);
FORCEPROP 0 LAST CDS_LOCATION Q1W4
J 0
(-7500 2500);
PAINT MONO (-7500 2500);
DISPLAY INVISIBLE (-7500 2500);
FORCEPROP 1 LAST PATH I3
J 0
(-7500 2500);
DISPLAY 0.978723 (-7500 2500);
PAINT BLUE (-7500 2500);
DISPLAY INVISIBLE (-7500 2500);
FORCEPROP 0 LAST CDS_SEC 1
J 0
(-7500 2500);
PAINT MONO (-7500 2500);
DISPLAY INVISIBLE (-7500 2500);
FORCEPROP 2 LAST ROOM UART_MUX
J 0
(-7500 2500);
DISPLAY 1.021277 (-7500 2500);
PAINT ORANGE (-7500 2500);
DISPLAY INVISIBLE (-7500 2500);
FORCEPROP 2 LAST BOM_COST DEBUG
J 0
(-7500 2550);
DISPLAY 1.021277 (-7500 2550);
PAINT ORANGE (-7500 2550);
DISPLAY INVISIBLE (-7500 2550);
FORCEPROP 2 LAST CDS_LIB mstr_discrete
J 0
(-7700 2450);
PAINT MONO (-7700 2450);
DISPLAY INVISIBLE (-7700 2450);
FORCEPROP 1 LAST PACK_TYPE SMLF
J 0
(-7500 2300);
DISPLAY 0.978723 (-7500 2300);
PAINT SKYBLUE (-7500 2300);
DISPLAY INVISIBLE (-7500 2300);
FORCEPROP 2 LAST SEC 1
J 0
(-7500 2550);
DISPLAY 0.680851 (-7500 2550);
PAINT MONO (-7500 2550);
DISPLAY INVISIBLE (-7500 2550);
FORCEPROP 2 LAST SEC_TYPE SMLF
J 0
(-7500 2550);
DISPLAY 1.021277 (-7500 2550);
PAINT ORANGE (-7500 2550);
DISPLAY INVISIBLE (-7500 2550);
FORCEADD GND..1
(-7700 2150);
FORCEPROP 3 LASTPIN (-7700 2200) SIG_NAME GND\g
J 0
(-7690 2210);
DISPLAY 0.659574 (-7690 2210);
PAINT MONO (-7690 2210);
DISPLAY INVISIBLE (-7690 2210);
FORCEPROP 1 LAST PATH I4
J 0
(-7625 2150);
DISPLAY 0.872340 (-7625 2150);
PAINT AQUA (-7625 2150);
DISPLAY INVISIBLE (-7625 2150);
FORCEPROP 2 LAST CDS_LIB mstr_symbols
J 0
(-7700 2150);
PAINT MONO (-7700 2150);
DISPLAY INVISIBLE (-7700 2150);
FORCEPROP 1 LAST SIZE 1B
J 0
(-7625 2100);
DISPLAY 0.872340 (-7625 2100);
PAINT AQUA (-7625 2100);
DISPLAY INVISIBLE (-7625 2100);
FORCEPROP 1 LAST VOLTAGE 0.0V
J 0
(-7745 2107);
DISPLAY 0.340426 (-7745 2107);
PAINT SKYBLUE (-7745 2107);
DISPLAY INVISIBLE (-7745 2107);
FORCEPROP 1 LAST BODY_TYPE PLUMBING
J 0
(-7745 2107);
DISPLAY 0.340426 (-7745 2107);
PAINT GREEN (-7745 2107);
DISPLAY INVISIBLE (-7745 2107);
FORCEPROP 1 LAST HDL_POWER GND
J 0
(-7700 2300);
DISPLAY 0.872340 (-7700 2300);
PAINT GREEN (-7700 2300);
DISPLAY INVISIBLE (-7700 2300);
FORCEADD P3V3_STBY..1
(-8725 2800);
FORCEPROP 3 LASTPIN (-8725 2750) SIG_NAME P3V3_STBY\g
J 0
(-8715 2760);
DISPLAY 0.659574 (-8715 2760);
PAINT MONO (-8715 2760);
DISPLAY INVISIBLE (-8715 2760);
FORCEPROP 1 LAST SIZE 1B
J 0
(-8680 2822);
DISPLAY 0.340426 (-8680 2822);
PAINT GREEN (-8680 2822);
DISPLAY INVISIBLE (-8680 2822);
FORCEPROP 1 LAST VOLTAGE 3.3V
J 0
(-8770 2757);
DISPLAY 0.340426 (-8770 2757);
PAINT SKYBLUE (-8770 2757);
DISPLAY INVISIBLE (-8770 2757);
FORCEPROP 2 LAST CDS_LIB mstr_symbols
J 0
(-8725 2800);
PAINT MONO (-8725 2800);
DISPLAY INVISIBLE (-8725 2800);
FORCEPROP 1 LAST PATH I5
J 0
(-8680 2802);
DISPLAY 0.340426 (-8680 2802);
PAINT GREEN (-8680 2802);
DISPLAY INVISIBLE (-8680 2802);
FORCEPROP 1 LAST BODY_TYPE PLUMBING
J 0
(-8770 2757);
DISPLAY 0.340426 (-8770 2757);
PAINT GREEN (-8770 2757);
DISPLAY INVISIBLE (-8770 2757);
FORCEPROP 1 LAST HDL_POWER P3V3_STBY
J 0
(-9025 2675);
DISPLAY 0.872340 (-9025 2675);
PAINT ORANGE (-9025 2675);
DISPLAY INVISIBLE (-9025 2675);
FORCEADD RES..1
R 1
(-7700 2900);
FORCEPROP 1 LAST PART_NUMBER G21796-016
J 0
(-7625 2800);
DISPLAY 0.617021 (-7625 2800);
PAINT BLUE (-7625 2800);
FORCEPROP 1 LAST PACK_TYPE 0402
J 0
(-7625 2750);
DISPLAY 0.617021 (-7625 2750);
PAINT SKYBLUE (-7625 2750);
FORCEPROP 1 LAST MATERIAL CHIP
J 0
(-7625 2850);
DISPLAY 0.617021 (-7625 2850);
PAINT SKYBLUE (-7625 2850);
FORCEPROP 1 LASTPIN (-7700 2800) $PN 1
R 1
J 0
(-7712 2812);
DISPLAY 0.787234 (-7712 2812);
PAINT ORANGE (-7712 2812);
FORCEPROP 1 LASTPIN (-7700 3000) $PN 2
R 1
J 0
(-7712 2962);
DISPLAY 0.787234 (-7712 2962);
PAINT ORANGE (-7712 2962);
FORCEPROP 1 LAST LOCATION R1W7
J 0
(-7625 3050);
DISPLAY 0.617021 (-7625 3050);
PAINT AQUA (-7625 3050);
FORCEPROP 1 LAST WATTAGE 1/16W
J 2
(-7500 2900);
DISPLAY 0.617021 (-7500 2900);
PAINT SKYBLUE (-7500 2900);
FORCEPROP 1 LAST TOLERANCE 1%
J 0
(-7625 2950);
DISPLAY 0.617021 (-7625 2950);
PAINT SKYBLUE (-7625 2950);
FORCEPROP 1 LAST VALUE 10.0K
J 2
(-7525 3000);
DISPLAY 0.617021 (-7525 3000);
PAINT SKYBLUE (-7525 3000);
FORCEPROP 2 LAST SEC_TYPE 0402
J 0
(-7625 3100);
DISPLAY 1.021277 (-7625 3100);
PAINT ORANGE (-7625 3100);
DISPLAY INVISIBLE (-7625 3100);
FORCEPROP 2 LAST SEC 1
J 0
(-7625 3100);
DISPLAY 0.680851 (-7625 3100);
PAINT MONO (-7625 3100);
DISPLAY INVISIBLE (-7625 3100);
FORCEPROP 0 LAST CDS_LOCATION R1W7
R 1
J 0
(-7625 3100);
PAINT MONO (-7625 3100);
DISPLAY INVISIBLE (-7625 3100);
FORCEPROP 1 LAST PATH I6
R 1
J 0
(-7850 2850);
DISPLAY 0.978723 (-7850 2850);
PAINT WHITE (-7850 2850);
DISPLAY INVISIBLE (-7850 2850);
FORCEPROP 0 LAST ROOM SB
R 1
J 0
(-7850 2850);
DISPLAY 1.021277 (-7850 2850);
PAINT ORANGE (-7850 2850);
DISPLAY INVISIBLE (-7850 2850);
FORCEPROP 2 LAST CDS_LIB mstr_discrete
R 1
J 0
(-7700 2900);
PAINT MONO (-7700 2900);
DISPLAY INVISIBLE (-7700 2900);
FORCEADD P3V3_STBY..1
(-7700 3100);
FORCEPROP 3 LASTPIN (-7700 3050) SIG_NAME P3V3_STBY\g
J 0
(-7690 3060);
DISPLAY 0.659574 (-7690 3060);
PAINT MONO (-7690 3060);
DISPLAY INVISIBLE (-7690 3060);
FORCEPROP 1 LAST PATH I7
J 0
(-7655 3102);
DISPLAY 0.340426 (-7655 3102);
PAINT GREEN (-7655 3102);
DISPLAY INVISIBLE (-7655 3102);
FORCEPROP 2 LAST CDS_LIB mstr_symbols
J 0
(-7700 3100);
PAINT MONO (-7700 3100);
DISPLAY INVISIBLE (-7700 3100);
FORCEPROP 1 LAST SIZE 1B
J 0
(-7655 3122);
DISPLAY 0.340426 (-7655 3122);
PAINT GREEN (-7655 3122);
DISPLAY INVISIBLE (-7655 3122);
FORCEPROP 1 LAST VOLTAGE 3.3V
J 0
(-7745 3057);
DISPLAY 0.340426 (-7745 3057);
PAINT SKYBLUE (-7745 3057);
DISPLAY INVISIBLE (-7745 3057);
FORCEPROP 1 LAST BODY_TYPE PLUMBING
J 0
(-7745 3057);
DISPLAY 0.340426 (-7745 3057);
PAINT GREEN (-7745 3057);
DISPLAY INVISIBLE (-7745 3057);
FORCEPROP 1 LAST HDL_POWER P3V3_STBY
J 0
(-8000 2975);
DISPLAY 0.872340 (-8000 2975);
PAINT ORANGE (-8000 2975);
DISPLAY INVISIBLE (-8000 2975);
FORCEADD FET_N_DUAL..5
(-5925 2800);
FORCEPROP 1 LAST LOCATION Q1W4
J 0
(-5725 2800);
DISPLAY 0.617021 (-5725 2800);
PAINT AQUA (-5725 2800);
FORCEPROP 1 LAST PART_NUMBER D24280-001
J 0
(-5725 2600);
DISPLAY 0.617021 (-5725 2600);
PAINT BLUE (-5725 2600);
FORCEPROP 1 LAST VALUE 2N7002DW
J 0
(-5725 2750);
DISPLAY 0.617021 (-5725 2750);
PAINT SKYBLUE (-5725 2750);
FORCEPROP 1 LASTPIN (-6125 2700) $PN 5
J 2
(-6122 2715);
DISPLAY 0.872340 (-6122 2715);
PAINT WHITE (-6122 2715);
FORCEPROP 1 LASTPIN (-5925 2600) $PN 4
J 2
(-5867 2600);
DISPLAY 0.872340 (-5867 2600);
PAINT WHITE (-5867 2600);
FORCEPROP 1 LASTPIN (-5925 3000) $PN 3
J 2
(-5872 2965);
DISPLAY 0.872340 (-5872 2965);
PAINT WHITE (-5872 2965);
FORCEPROP 1 LAST MATERIAL FET
J 0
(-5725 2700);
DISPLAY 0.617021 (-5725 2700);
PAINT SKYBLUE (-5725 2700);
FORCEPROP 0 LAST CDS_LOCATION Q1W4
J 0
(-5725 2850);
PAINT MONO (-5725 2850);
DISPLAY INVISIBLE (-5725 2850);
FORCEPROP 1 LAST PATH I8
J 0
(-5725 2850);
DISPLAY 0.978723 (-5725 2850);
PAINT BLUE (-5725 2850);
DISPLAY INVISIBLE (-5725 2850);
FORCEPROP 0 LAST CDS_SEC 2
J 0
(-5725 2850);
PAINT MONO (-5725 2850);
DISPLAY INVISIBLE (-5725 2850);
FORCEPROP 2 LAST CDS_LIB mstr_discrete
J 0
(-5925 2800);
PAINT MONO (-5925 2800);
DISPLAY INVISIBLE (-5925 2800);
FORCEPROP 2 LAST ROOM UART_MUX
J 0
(-5725 2850);
DISPLAY 1.021277 (-5725 2850);
PAINT ORANGE (-5725 2850);
DISPLAY INVISIBLE (-5725 2850);
FORCEPROP 2 LAST BOM_COST DEBUG
J 0
(-5725 2900);
DISPLAY 1.021277 (-5725 2900);
PAINT ORANGE (-5725 2900);
DISPLAY INVISIBLE (-5725 2900);
FORCEPROP 1 LAST PACK_TYPE SMLF
J 0
(-5725 2650);
DISPLAY 0.978723 (-5725 2650);
PAINT SKYBLUE (-5725 2650);
DISPLAY INVISIBLE (-5725 2650);
FORCEPROP 2 LAST SEC 2
J 0
(-5725 2900);
DISPLAY 0.680851 (-5725 2900);
PAINT MONO (-5725 2900);
DISPLAY INVISIBLE (-5725 2900);
FORCEPROP 2 LAST SEC_TYPE SMLF
J 0
(-5725 2900);
DISPLAY 1.021277 (-5725 2900);
PAINT ORANGE (-5725 2900);
DISPLAY INVISIBLE (-5725 2900);
FORCEADD GND..1
(-5925 2500);
FORCEPROP 3 LASTPIN (-5925 2550) SIG_NAME GND\g
J 0
(-5915 2560);
DISPLAY 0.659574 (-5915 2560);
PAINT MONO (-5915 2560);
DISPLAY INVISIBLE (-5915 2560);
FORCEPROP 1 LAST PATH I9
J 0
(-5850 2500);
DISPLAY 0.872340 (-5850 2500);
PAINT AQUA (-5850 2500);
DISPLAY INVISIBLE (-5850 2500);
FORCEPROP 1 LAST SIZE 1B
J 0
(-5850 2450);
DISPLAY 0.872340 (-5850 2450);
PAINT AQUA (-5850 2450);
DISPLAY INVISIBLE (-5850 2450);
FORCEPROP 1 LAST VOLTAGE 0.0V
J 0
(-5970 2457);
DISPLAY 0.340426 (-5970 2457);
PAINT SKYBLUE (-5970 2457);
DISPLAY INVISIBLE (-5970 2457);
FORCEPROP 2 LAST CDS_LIB mstr_symbols
J 0
(-5925 2500);
PAINT MONO (-5925 2500);
DISPLAY INVISIBLE (-5925 2500);
FORCEPROP 1 LAST BODY_TYPE PLUMBING
J 0
(-5970 2457);
DISPLAY 0.340426 (-5970 2457);
PAINT GREEN (-5970 2457);
DISPLAY INVISIBLE (-5970 2457);
FORCEPROP 1 LAST HDL_POWER GND
J 0
(-5925 2650);
DISPLAY 0.872340 (-5925 2650);
PAINT GREEN (-5925 2650);
DISPLAY INVISIBLE (-5925 2650);
FORCEADD INTEL_CORP_BPAGE..1
(-2525 1650);
FORCEPROP 1 LAST CDS_CON_LAST_MODIFIED Fri Jun 16 17:49:31 2017
J 0
(-3950 1975);
PAINT ORANGE (-3950 1975);
DISPLAY INVISIBLE (-3950 1975);
FORCEPROP 2 LAST CUSTOM_TXT_CDS <XR_PAGE_TITLE>
J 0
(-10415 6900);
DISPLAY 0.638298 (-10415 6900);
PAINT PINK (-10415 6900);
DISPLAY INVISIBLE (-10415 6900);
FORCEPROP 2 LAST CUSTOM_TXT_CDS <CON_LAST_MODIFIED>
J 0
(-6525 1750);
PAINT ORANGE (-6525 1750);
FORCEPROP 2 LAST CUSTOM_TXT_CDS <CURRENT_DESIGN_SHEET> OF <TOTAL_DESIGN_SHEETS>
J 0
(-3025 1675);
PAINT ORANGE (-3025 1675);
FORCEPROP 1 LAST SCH_TITLE MEZZ PRESENT CIRCUIT
J 0
(-10475 1700);
DISPLAY 2.468085 (-10475 1700);
PAINT ORANGE (-10475 1700);
FORCEPROP 2 LAST CDS_LIB mstr_symbols
J 0
(-2525 1650);
PAINT MONO (-2525 1650);
DISPLAY INVISIBLE (-2525 1650);
FORCEPROP 2 LAST PAGE_BORDER TRUE
J 0
(-10415 6900);
DISPLAY 0.638298 (-10415 6900);
PAINT PINK (-10415 6900);
DISPLAY INVISIBLE (-10415 6900);
FORCEPROP 1 LAST COMMENT_BODY TRUE
J 0
(-2513 1662);
DISPLAY 0.468085 (-2513 1662);
PAINT GREEN (-2513 1662);
DISPLAY INVISIBLE (-2513 1662);
FORCEPROP 2 LAST CDS_XR_PAGE_TITLE CR-250 : @BASEBOARD_FAB2_LIB.BASEBOARD_FAB2(SCH_1):PAGE250
J 0
(-10415 6900);
DISPLAY 0.638298 (-10415 6900);
PAINT PINK (-10415 6900);
DISPLAY INVISIBLE (-10415 6900);
WIRE 16 -1 (-6525 3875)(-6525 3925);
WIRE 16 -1 (-8300 5675)(-8300 5625);
WIRE 16 -1 (-7350 5175)(-7350 5125);
WIRE 16 -1 (-7350 4850)(-7350 4800);
WIRE 16 -1 (-7350 4050)(-7350 4000);
WIRE 16 -1 (-8300 4525)(-8300 4475);
WIRE 16 -1 (-7700 2250)(-7700 2200);
WIRE 16 -1 (-8725 2750)(-8725 2700);
WIRE 16 -1 (-7700 3050)(-7700 3000);
WIRE 16 -1 (-5925 2550)(-5925 2600);
WIRE 3 2175 (-8675 5825)(-7625 5825);
WIRE 3 2175 (-7625 5125)(-7625 5825);
WIRE 3 2175 (-8675 5125)(-8675 5825);
WIRE 3 2175 (-8675 5125)(-7625 5125);
WIRE 16 -1 (-7350 5575)(-7350 5625);
WIRE 16 -1 (-7350 5625)(-6375 5625);
FORCEPROP 2 LAST SIG_NAME FM_OCP_MEZZA_PRES
J 0
(-7110 5635);
DISPLAY 0.808511 (-7110 5635);
PAINT ORANGE (-7110 5635);
WIRE 3 2175 (-7175 5725)(-5725 5725);
WIRE 3 2175 (-5725 5525)(-5725 5725);
WIRE 3 2175 (-7175 5525)(-7175 5725);
WIRE 3 2175 (-7175 5525)(-5725 5525);
WIRE 3 2175 (-9775 2100)(-9775 3200);
WIRE 3 2175 (-9775 3200)(-3675 3200);
WIRE 3 2175 (-9775 2100)(-3675 2100);
WIRE 3 2175 (-3675 2100)(-3675 3200);
WIRE 16 -1 (-8350 5275)(-8300 5275);
WIRE 16 -1 (-8300 5275)(-8300 5375);
WIRE 16 -1 (-8300 5275)(-7550 5275);
FORCEPROP 0 LAST CDS_PHYS_NET_NAME FM_OCP_MEZZA_PRES_N
J 0
(-8037 5314);
PAINT MONO (-8037 5314);
DISPLAY INVISIBLE (-8037 5314);
FORCEPROP 0 LAST SIG_NAME FM_OCP_MEZZA_PRES_N
J 1
(-7937 5285);
DISPLAY 0.617021 (-7937 5285);
PAINT ORANGE (-7937 5285);
WIRE 3 2175 (-6475 5125)(-5025 5125);
WIRE 3 2175 (-5025 4925)(-5025 5125);
WIRE 3 2175 (-6475 4925)(-6475 5125);
WIRE 3 2175 (-6475 4925)(-5025 4925);
WIRE 16 -1 (-6425 2300)(-5025 2300);
WIRE 16 -1 (-6425 2700)(-6425 2300);
WIRE 16 -1 (-6425 2700)(-6125 2700);
WIRE 16 -1 (-7700 2800)(-7700 2700);
WIRE 16 -1 (-7700 2650)(-7700 2700);
WIRE 16 -1 (-7700 2700)(-6425 2700);
FORCEPROP 2 LAST SIG_NAME FM_OCP_MEZZC_PRES_LVT3_BMC
J 0
(-7460 2710);
DISPLAY 0.808511 (-7460 2710);
PAINT ORANGE (-7460 2710);
WIRE 16 -1 (-5925 3050)(-5925 3000);
WIRE 16 -1 (-5925 3050)(-4425 3050);
FORCEPROP 0 LAST SIG_NAME FM_OCP_MEZZC_PRES_1V05_PCH_N
J 1
(-5237 3060);
DISPLAY 0.765957 (-5237 3060);
PAINT ORANGE (-5237 3060);
WIRE 3 2175 (-6325 4275)(-4875 4275);
WIRE 3 2175 (-4875 4275)(-4875 4475);
WIRE 3 2175 (-6325 4275)(-6325 4475);
WIRE 3 2175 (-6325 4475)(-4875 4475);
WIRE 3 2175 (-5725 2950)(-3875 2950);
WIRE 3 2175 (-3875 3150)(-3875 2950);
WIRE 3 2175 (-5725 3150)(-5725 2950);
WIRE 3 2175 (-5725 3150)(-3875 3150);
WIRE 16 -1 (-6525 4375)(-6525 4325);
WIRE 16 -1 (-6525 4375)(-5425 4375);
FORCEPROP 0 LAST SIG_NAME FM_OCP_MEZZB_PRES_1V05_PCH_N
J 1
(-5987 4385);
DISPLAY 0.617021 (-5987 4385);
PAINT ORANGE (-5987 4385);
WIRE 16 -1 (-8775 2350)(-8725 2350);
WIRE 16 -1 (-8725 2350)(-8725 2450);
WIRE 16 -1 (-7900 2350)(-8725 2350);
FORCEPROP 0 LAST CDS_PHYS_NET_NAME FM_OCP_MEZZA_PRES_N_CONN
J 0
(-8387 2389);
PAINT MONO (-8387 2389);
DISPLAY INVISIBLE (-8387 2389);
FORCEPROP 0 LAST SIG_NAME FM_OCP_MEZZC_PRES_N
J 1
(-8337 2360);
DISPLAY 0.617021 (-8337 2360);
PAINT ORANGE (-8337 2360);
WIRE 3 2175 (-8725 6125)(-4775 6125);
WIRE 3 2175 (-4775 3725)(-4775 6125);
WIRE 3 2175 (-8725 3725)(-8725 6125);
WIRE 3 2175 (-8725 3725)(-4775 3725);
WIRE 3 2175 (-8675 4675)(-7625 4675);
WIRE 3 2175 (-7625 3975)(-7625 4675);
WIRE 3 2175 (-8675 3975)(-8675 4675);
WIRE 3 2175 (-8675 3975)(-7625 3975);
WIRE 16 -1 (-8350 4150)(-8300 4150);
WIRE 16 -1 (-8300 4150)(-8300 4225);
WIRE 16 -1 (-8300 4150)(-7550 4150);
FORCEPROP 0 LAST CDS_PHYS_NET_NAME FM_OCP_MEZZB_PRES_N
J 0
(-8037 4189);
PAINT MONO (-8037 4189);
DISPLAY INVISIBLE (-8037 4189);
FORCEPROP 0 LAST SIG_NAME FM_OCP_MEZZB_PRES_N
J 1
(-7937 4160);
DISPLAY 0.617021 (-7937 4160);
PAINT ORANGE (-7937 4160);
WIRE 3 2175 (-9225 2200)(-8025 2200);
WIRE 3 2175 (-8025 2900)(-8025 2200);
WIRE 3 2175 (-9225 2900)(-9225 2200);
WIRE 3 2175 (-9225 2900)(-8025 2900);
WIRE 16 -1 (-5425 5025)(-6825 5025);
FORCEPROP 0 LAST SIG_NAME FM_OCP_MEZZB_PRES_LVT3_BMC
J 1
(-6037 5035);
DISPLAY 0.617021 (-6037 5035);
PAINT ORANGE (-6037 5035);
WIRE 16 -1 (-7350 4600)(-7350 4500);
WIRE 16 -1 (-7350 4450)(-7350 4500);
WIRE 16 -1 (-7350 4500)(-6825 4500);
WIRE 16 -1 (-6825 5025)(-6825 4500);
WIRE 16 -1 (-6725 4025)(-6825 4025);
WIRE 16 -1 (-6825 4025)(-6825 4500);
DOT 1 (-7350 4500);
DOT 1 (-8300 4150);
DOT 1 (-8300 5275);
DOT 1 (-6825 4500);
DOT 1 (-6425 2700);
DOT 1 (-7700 2700);
DOT 1 (-8725 2350);
FORCENOTE
TP FAB1 RENAME 1218
(-6460 4866) 0;
DISPLAY LEFT (-6460 4866);
DISPLAY 1.021277 (-6460 4866);
PAINT RED (-6460 4866);
FORCENOTE
VGS(TH)=1V~2V
(-8000 5150) 0;
DISPLAY LEFT (-8000 5150);
DISPLAY 1.021277 (-8000 5150);
PAINT PURPLE (-8000 5150);
FORCENOTE
TP FAB1 RENAME 1218
(-9175 2925) 0;
DISPLAY LEFT (-9175 2925);
DISPLAY 1.021277 (-9175 2925);
PAINT RED (-9175 2925);
FORCENOTE
VGS(TH)=1V~2V
(-8000 4025) 0;
DISPLAY LEFT (-8000 4025);
DISPLAY 1.021277 (-8000 4025);
PAINT PURPLE (-8000 4025);
FORCENOTE
TP FAB1 RENAME 1218
(-8626 3919) 0;
DISPLAY LEFT (-8626 3919);
DISPLAY 1.021277 (-8626 3919);
PAINT RED (-8626 3919);
FORCENOTE
TP FAB1 RENAME 1218
(-8589 5063) 0;
DISPLAY LEFT (-8589 5063);
DISPLAY 1.021277 (-8589 5063);
PAINT RED (-8589 5063);
FORCENOTE
TP FAB1  ADD MEZZ PRESENT CIRCUIT 1210
(-8712 6156) 0;
DISPLAY LEFT (-8712 6156);
DISPLAY 1.021277 (-8712 6156);
PAINT RED (-8712 6156);
FORCENOTE
TP FAB1  ADD MEZZ  C PRESENT CIRCUIT 1214
(-9775 3250) 0;
DISPLAY LEFT (-9775 3250);
DISPLAY 1.021277 (-9775 3250);
PAINT RED (-9775 3250);
FORCENOTE
TP FAB1 RENAME 1218
(-6941 5465) 0;
DISPLAY LEFT (-6941 5465);
DISPLAY 1.021277 (-6941 5465);
PAINT RED (-6941 5465);
FORCENOTE
TP FAB1 RENAME 1218
(-5425 2875) 0;
DISPLAY LEFT (-5425 2875);
DISPLAY 1.021277 (-5425 2875);
PAINT RED (-5425 2875);
FORCENOTE
VGS(TH)=1V~2V
(-8600 2250) 0;
DISPLAY LEFT (-8600 2250);
DISPLAY 1.021277 (-8600 2250);
PAINT PURPLE (-8600 2250);
FORCENOTE
TP FAB1 RENAME 1218
(-6000 4200) 0;
DISPLAY LEFT (-6000 4200);
DISPLAY 1.021277 (-6000 4200);
PAINT RED (-6000 4200);
QUIT
